# BASEBOARD_FAB2 (Tioga Pass) — schematic netlist excerpt (pin names and nets, part order shuffled) for the footprints in the layout excerpt that follows; sources: Cadence DE-HDL packaged netlist, KiCad conversion of Wiwynn_Tioga_Pass_MB.brd

R6T6  RES  150.0 1% CHIP  pkg 0402  page 112 : A = PVCCIO_CPU1 ; B = XDP_CPU1_TDI
C7P10  CAP  100UF 4V 20% X5R  pkg 0805  page 76 : A = PVCCMCP_CPU1 ; B = GND
R25W6  120R2F-GP  1%  pkg RCL_GP  page 151 : \1\ = GND ; \2\ = BMC_M_RAS_N

(kicad_pcb
	(version 20260206)
	(generator "pcbnew")
	(generator_version "10.0")
	(general
		(thickness 1.6)
		(legacy_teardrops no)
	)
	(paper "A4")
	(title_block
		(title "Wiwynn_Tioga_Pass_MB.brd")
		(comment 1 "Tioga Pass / footprints 2585-2587 of 4770")
	)
	(layers
		(0 "F.Cu" signal "TOP")
		(4 "In1.Cu" signal "L2GND")
		(6 "In2.Cu" signal "L3")
		(8 "In3.Cu" signal "L4GND")
		(10 "In4.Cu" signal "L5")
		(12 "In5.Cu" signal "L6GND")
		(14 "In6.Cu" signal "L7VCC")
		(16 "In7.Cu" signal "L8VCC")
		(18 "In8.Cu" signal "L9GND")
		(20 "In9.Cu" signal "L10")
		(22 "In10.Cu" signal "L11GND")
		(24 "In11.Cu" signal "L12")
		(26 "In12.Cu" signal "L13GND")
		(2 "B.Cu" signal "BOTTOM")
		(9 "F.Adhes" user "F.Adhesive")
		(11 "B.Adhes" user "B.Adhesive")
		(13 "F.Paste" user "Package Geometry/Pastemask Top")
		(15 "B.Paste" user "Package Geometry/Pastemask Bottom")
		(5 "F.SilkS" user "Ref Des/Silkscreen Top")
		(7 "B.SilkS" user "Ref Des/Silkscreen Bottom")
		(1 "F.Mask" user "Board Geometry/Soldermask Top")
		(3 "B.Mask" user "Board Geometry/Soldermask Bottom")
		(17 "Dwgs.User" user "User.Drawings")
		(19 "Cmts.User" user "User.Comments")
		(21 "Eco1.User" user "User.Eco1")
		(23 "Eco2.User" user "User.Eco2")
		(25 "Edge.Cuts" user "Board Geometry/Outline")
		(27 "Margin" user)
		(31 "F.CrtYd" user "Package Geometry/Place Bound Top")
		(29 "B.CrtYd" user "Package Geometry/Place Bound Bottom")
		(35 "F.Fab" user "Ref Des/Assembly Top")
		(33 "B.Fab" user "Ref Des/Assembly Bottom")
	)
	(footprint ""
		(layer "B.Cu")
		(at 177.906426 -21.0439 90)
		(property "Reference" "R6T6"
			(at 0 0 90)
			(layer "B.SilkS")
			(hide yes)
			(effects
				(font
					(size 1.27 1.27)
				)
				(justify mirror)
			)
		)
		(property "Value" ""
			(at 0 0 90)
			(layer "B.Fab")
			(effects
				(font
					(size 1.27 1.27)
				)
				(justify mirror)
			)
		)
		(duplicate_pad_numbers_are_jumpers no)
		(fp_poly
			(pts
				(xy 0.2794 -0.1016) (xy -0.2794 -0.1016) (xy -0.2794 0.9906) (xy 0.2794 0.9906)
			)
			(stroke
				(width 0)
				(type default)
			)
			(fill no)
			(layer "B.CrtYd")
		)
		(fp_line
			(start 0.2794 -0.1016)
			(end 0.2794 0.9906)
			(stroke
				(width 0.1)
				(type default)
			)
			(layer "B.Fab")
		)
		(fp_line
			(start -0.2794 -0.1016)
			(end 0.2794 -0.1016)
			(stroke
				(width 0.1)
				(type default)
			)
			(layer "B.Fab")
		)
		(fp_line
			(start 0.2794 0.9906)
			(end -0.2794 0.9906)
			(stroke
				(width 0.1)
				(type default)
			)
			(layer "B.Fab")
		)
		(fp_line
			(start -0.2794 0.9906)
			(end -0.2794 -0.1016)
			(stroke
				(width 0.1)
				(type default)
			)
			(layer "B.Fab")
		)
		(pad "1" smd rect
			(at 0 0 270)
			(size 0.508 0.508)
			(layers "B.Cu" "B.Mask" "B.Paste")
			(net "PVCCIO_CPU1")
		)
		(pad "2" smd rect
			(at 0 0.889 270)
			(size 0.508 0.508)
			(layers "B.Cu" "B.Mask" "B.Paste")
			(net "XDP_CPU1_TDI")
		)
		(zone
			(layer "B.Cu")
			(hatch none 0.5)
			(connect_pads
				(clearance 0)
			)
			(min_thickness 0.25)
			(keepout
				(tracks allowed)
				(vias not_allowed)
				(pads allowed)
				(copperpour not_allowed)
				(footprints allowed)
			)
			(placement
				(enabled no)
				(sheetname "")
			)
			(fill
				(thermal_gap 0.5)
				(thermal_bridge_width 0.5)
				(island_removal_mode 0)
			)
			(polygon
				(pts
					(xy 178.160426 -21.2979) (xy 178.160426 -20.7899) (xy 178.541426 -20.7899) (xy 178.541426 -21.2979)
				)
			)
		)
		(zone
			(layer "B.Cu")
			(hatch none 0.5)
			(connect_pads
				(clearance 0)
			)
			(min_thickness 0.25)
			(keepout
				(tracks not_allowed)
				(vias allowed)
				(pads allowed)
				(copperpour not_allowed)
				(footprints allowed)
			)
			(placement
				(enabled no)
				(sheetname "")
			)
			(fill
				(thermal_gap 0.5)
				(thermal_bridge_width 0.5)
				(island_removal_mode 0)
			)
			(polygon
				(pts
					(xy 178.541426 -21.2979) (xy 178.541426 -20.7899) (xy 178.160426 -20.7899) (xy 178.160426 -21.2979)
				)
			)
		)
	)
	(footprint ""
		(layer "B.Cu")
		(at 446.381632 -35.8775 90)
		(property "Reference" "R25W6"
			(at 0 0 90)
			(layer "B.SilkS")
			(hide yes)
			(effects
				(font
					(size 1.27 1.27)
				)
				(justify mirror)
			)
		)
		(property "Value" "*"
			(at -0.064008 -4.108196 90)
			(unlocked yes)
			(layer "B.Fab")
			(hide yes)
			(effects
				(font
					(size 1.27 1.016)
					(thickness 0.1524)
				)
				(justify mirror)
			)
		)
		(property "Device Type" "120R2F-GP_RCL_GP-120R2F-GP,64.A"
			(at -0.064008 -5.632196 90)
			(unlocked yes)
			(layer "B.Fab")
			(hide yes)
			(effects
				(font
					(size 1.27 1.016)
					(thickness 0.1524)
				)
				(justify mirror)
			)
		)
		(duplicate_pad_numbers_are_jumpers no)
		(fp_line
			(start 0.508 -0.9398)
			(end 0.508 0.9398)
			(stroke
				(width 0.1524)
				(type default)
			)
			(layer "B.SilkS")
		)
		(fp_line
			(start -0.508 -0.9398)
			(end 0.508 -0.9398)
			(stroke
				(width 0.1524)
				(type default)
			)
			(layer "B.SilkS")
		)
		(fp_rect
			(start 0.508 0.9398)
			(end -0.508 -0.9398)
			(stroke
				(width 0)
				(type default)
			)
			(fill no)
			(layer "B.CrtYd")
		)
		(fp_rect
			(start 0.508 0.9398)
			(end -0.508 -0.9398)
			(stroke
				(width 0)
				(type default)
			)
			(fill no)
			(layer "B.Fab")
		)
		(pad "1" smd custom
			(at 0 -0.4445 270)
			(size 0.1397 0.1397)
			(layers "B.Cu" "B.Mask" "B.Paste")
			(net "GND")
			(options
				(clearance outline)
				(anchor circle)
			)
			(primitives
				(gr_poly
					(pts
						(arc
							(start -0.1778 0.2794)
							(mid -0.249642 0.249642)
							(end -0.2794 0.1778)
						)
						(arc
							(start -0.2794 -0.1778)
							(mid -0.249642 -0.249642)
							(end -0.1778 -0.2794)
						)
						(arc
							(start 0.1778 -0.2794)
							(mid 0.249642 -0.249642)
							(end 0.2794 -0.1778)
						)
						(arc
							(start 0.2794 0.1778)
							(mid 0.249642 0.249642)
							(end 0.1778 0.2794)
						)
					)
					(width 0)
					(fill yes)
				)
			)
		)
		(pad "2" smd custom
			(at 0 0.4445 270)
			(size 0.1397 0.1397)
			(layers "B.Cu" "B.Mask" "B.Paste")
			(net "BMC_M_RAS_N")
			(options
				(clearance outline)
				(anchor circle)
			)
			(primitives
				(gr_poly
					(pts
						(arc
							(start -0.1778 0.2794)
							(mid -0.249642 0.249642)
							(end -0.2794 0.1778)
						)
						(arc
							(start -0.2794 -0.1778)
							(mid -0.249642 -0.249642)
							(end -0.1778 -0.2794)
						)
						(arc
							(start 0.1778 -0.2794)
							(mid 0.249642 -0.249642)
							(end 0.2794 -0.1778)
						)
						(arc
							(start 0.2794 0.1778)
							(mid 0.249642 0.249642)
							(end 0.1778 0.2794)
						)
					)
					(width 0)
					(fill yes)
				)
			)
		)
	)
	(footprint ""
		(layer "B.Cu")
		(at 108.178854 -77.82814)
		(property "Reference" "C7P10"
			(at 0 0 0)
			(layer "B.SilkS")
			(hide yes)
			(effects
				(font
					(size 1.27 1.27)
				)
				(justify mirror)
			)
		)
		(property "Value" ""
			(at 0 0 0)
			(layer "B.Fab")
			(effects
				(font
					(size 1.27 1.27)
				)
				(justify mirror)
			)
		)
		(duplicate_pad_numbers_are_jumpers no)
		(fp_poly
			(pts
				(xy 0.7239 -0.2159) (xy -0.7239 -0.2159) (xy -0.7239 1.9939) (xy 0.7239 1.9939)
			)
			(stroke
				(width 0)
				(type default)
			)
			(fill no)
			(layer "B.CrtYd")
		)
		(fp_line
			(start -0.7239 -0.2159)
			(end 0.7239 -0.2159)
			(stroke
				(width 0.1)
				(type default)
			)
			(layer "B.Fab")
		)
		(fp_line
			(start -0.7239 1.9939)
			(end -0.7239 -0.2159)
			(stroke
				(width 0.1)
				(type default)
			)
			(layer "B.Fab")
		)
		(fp_line
			(start 0.7239 -0.2159)
			(end 0.7239 1.9939)
			(stroke
				(width 0.1)
				(type default)
			)
			(layer "B.Fab")
		)
		(fp_line
			(start 0.7239 1.9939)
			(end -0.7239 1.9939)
			(stroke
				(width 0.1)
				(type default)
			)
			(layer "B.Fab")
		)
		(pad "1" smd rect
			(at 0 0 180)
			(size 1.27 1.016)
			(layers "B.Cu" "B.Mask" "B.Paste")
			(net "PVCCMCP_CPU1")
		)
		(pad "2" smd rect
			(at 0 1.778 180)
			(size 1.27 1.016)
			(layers "B.Cu" "B.Mask" "B.Paste")
			(net "GND")
		)
		(zone
			(layer "B.Cu")
			(hatch none 0.5)
			(connect_pads
				(clearance 0)
			)
			(min_thickness 0.25)
			(keepout
				(tracks not_allowed)
				(vias allowed)
				(pads allowed)
				(copperpour not_allowed)
				(footprints allowed)
			)
			(placement
				(enabled no)
				(sheetname "")
			)
			(fill
				(thermal_gap 0.5)
				(thermal_bridge_width 0.5)
				(island_removal_mode 0)
			)
			(polygon
				(pts
					(xy 108.813854 -77.32014) (xy 107.543854 -77.32014) (xy 107.543854 -76.55814) (xy 108.813854 -76.55814)
				)
			)
		)
	)
)
